(kicad_pcb
	(version 20260206)
	(generator "pcbnew")
	(generator_version "10.0")
	(general
		(thickness 1.6)
		(legacy_teardrops no)
	)
	(paper "A4")
	(title_block
		(title "01162023_DA0F0TEBIF0_F0T_Expander_BD_F_brd_V02_OCP.brd")
		(comment 1 "Grand Teton / footprints 20-26 of 9728")
	)
	(layers
		(0 "F.Cu" signal "TOP")
		(4 "In1.Cu" signal "GND")
		(6 "In2.Cu" signal "VCC")
		(8 "In3.Cu" signal "VCC1")
		(10 "In4.Cu" signal "GND1")
		(12 "In5.Cu" signal "IN1")
		(14 "In6.Cu" signal "GND2")
		(16 "In7.Cu" signal "IN2")
		(18 "In8.Cu" signal "GND3")
		(20 "In9.Cu" signal "IN3")
		(22 "In10.Cu" signal "GND4")
		(24 "In11.Cu" signal "IN4")
		(26 "In12.Cu" signal "GND5")
		(28 "In13.Cu" signal "IN5")
		(30 "In14.Cu" signal "GND6")
		(32 "In15.Cu" signal "IN6")
		(34 "In16.Cu" signal "GND7")
		(2 "B.Cu" signal "BOTTOM")
		(9 "F.Adhes" user "F.Adhesive")
		(11 "B.Adhes" user "B.Adhesive")
		(13 "F.Paste" user "Package Geometry/Pastemask Top")
		(15 "B.Paste" user "Package Geometry/Pastemask Bottom")
		(5 "F.SilkS" user "Ref Des/Silkscreen Top")
		(7 "B.SilkS" user "Ref Des/Silkscreen Bottom")
		(1 "F.Mask" user "Board Geometry/Soldermask Top")
		(3 "B.Mask" user "Board Geometry/Soldermask Bottom")
		(17 "Dwgs.User" user "User.Drawings")
		(19 "Cmts.User" user "User.Comments")
		(21 "Eco1.User" user "User.Eco1")
		(23 "Eco2.User" user "User.Eco2")
		(25 "Edge.Cuts" user "Board Geometry/Outline")
		(27 "Margin" user)
		(31 "F.CrtYd" user "Package Geometry/Place Bound Top")
		(29 "B.CrtYd" user "Package Geometry/Place Bound Bottom")
		(35 "F.Fab" user "Ref Des/Assembly Top")
		(33 "B.Fab" user "Ref Des/Assembly Bottom")
	)
	(footprint ""
		(layer "F.Cu")
		(at 5.073396 -283.624782 180)
		(property "Reference" "PC217"
			(at 0 0 180)
			(layer "F.SilkS")
			(hide yes)
			(effects
				(font
					(size 1.27 1.27)
				)
			)
		)
		(property "Value" ""
			(at 0 0 180)
			(layer "F.Fab")
			(effects
				(font
					(size 1.27 1.27)
				)
			)
		)
		(duplicate_pad_numbers_are_jumpers no)
		(fp_line
			(start 2.750058 2.750058)
			(end 2.750058 0.9398)
			(stroke
				(width 0.1524)
				(type default)
			)
			(layer "F.SilkS")
		)
		(fp_line
			(start 2.750058 -0.9398)
			(end 2.750058 -2.750058)
			(stroke
				(width 0.1524)
				(type default)
			)
			(layer "F.SilkS")
		)
		(fp_line
			(start 2.750058 -2.750058)
			(end -1.988058 -2.750058)
			(stroke
				(width 0.1524)
				(type default)
			)
			(layer "F.SilkS")
		)
		(fp_line
			(start -1.988058 2.750058)
			(end 2.750058 2.750058)
			(stroke
				(width 0.1524)
				(type default)
			)
			(layer "F.SilkS")
		)
		(fp_line
			(start -1.988058 -2.750058)
			(end -2.750058 -1.988058)
			(stroke
				(width 0.1524)
				(type default)
			)
			(layer "F.SilkS")
		)
		(fp_line
			(start -2.750058 1.988058)
			(end -1.988058 2.750058)
			(stroke
				(width 0.1524)
				(type default)
			)
			(layer "F.SilkS")
		)
		(fp_line
			(start -2.750058 0.9398)
			(end -2.750058 1.988058)
			(stroke
				(width 0.1524)
				(type default)
			)
			(layer "F.SilkS")
		)
		(fp_line
			(start -2.750058 -1.988058)
			(end -2.750058 -0.9398)
			(stroke
				(width 0.1524)
				(type default)
			)
			(layer "F.SilkS")
		)
		(fp_line
			(start 2.750058 2.750058)
			(end 2.750058 -2.750058)
			(stroke
				(width 0.1)
				(type default)
			)
			(layer "F.Fab")
		)
		(fp_line
			(start 2.750058 -2.750058)
			(end -2.750058 -2.750058)
			(stroke
				(width 0.1)
				(type default)
			)
			(layer "F.Fab")
		)
		(fp_line
			(start -2.750058 2.750058)
			(end 2.750058 2.750058)
			(stroke
				(width 0.1)
				(type default)
			)
			(layer "F.Fab")
		)
		(fp_line
			(start -2.750058 -2.750058)
			(end -2.750058 2.750058)
			(stroke
				(width 0.1)
				(type default)
			)
			(layer "F.Fab")
		)
		(pad "1" smd rect
			(at -2.199894 0 270)
			(size 1.6002 3.0226)
			(layers "F.Cu" "F.Mask" "F.Paste")
			(net "P1V25_PEX0_R")
		)
		(pad "2" smd rect
			(at 2.199894 0 270)
			(size 1.6002 3.0226)
			(layers "F.Cu" "F.Mask" "F.Paste")
			(net "GND")
		)
	)
	(footprint ""
		(layer "F.Cu")
		(at 51.311048 -343.952322 90)
		(property "Reference" "C2181"
			(at 0 0 90)
			(layer "F.SilkS")
			(hide yes)
			(effects
				(font
					(size 1.27 1.27)
				)
			)
		)
		(property "Value" ""
			(at 0 0 90)
			(layer "F.Fab")
			(effects
				(font
					(size 1.27 1.27)
				)
			)
		)
		(duplicate_pad_numbers_are_jumpers no)
		(fp_line
			(start 0.299974 -0.150114)
			(end 0.299974 0.150114)
			(stroke
				(width 0.1)
				(type default)
			)
			(layer "F.Fab")
		)
		(fp_line
			(start -0.299974 -0.150114)
			(end 0.299974 -0.150114)
			(stroke
				(width 0.1)
				(type default)
			)
			(layer "F.Fab")
		)
		(fp_line
			(start 0.299974 0.150114)
			(end -0.299974 0.150114)
			(stroke
				(width 0.1)
				(type default)
			)
			(layer "F.Fab")
		)
		(fp_line
			(start -0.299974 0.150114)
			(end -0.299974 -0.150114)
			(stroke
				(width 0.1)
				(type default)
			)
			(layer "F.Fab")
		)
		(pad "1" smd rect
			(at -0.2667 0 90)
			(size 0.3048 0.381)
			(layers "F.Cu" "F.Mask" "F.Paste")
			(net "P5E_PEX0_STN4_TX_DN<65>")
		)
		(pad "2" smd rect
			(at 0.2667 0 90)
			(size 0.3048 0.381)
			(layers "F.Cu" "F.Mask" "F.Paste")
			(net "P5E_PEX0_STN4_TX_C_DN<65>")
		)
	)
	(footprint ""
		(layer "F.Cu")
		(at 376.809 -172.11802)
		(property "Reference" "R4713"
			(at 0 0 0)
			(layer "F.SilkS")
			(hide yes)
			(effects
				(font
					(size 1.27 1.27)
				)
			)
		)
		(property "Value" ""
			(at 0 0 0)
			(layer "F.Fab")
			(effects
				(font
					(size 1.27 1.27)
				)
			)
		)
		(duplicate_pad_numbers_are_jumpers no)
		(fp_line
			(start -0.7874 -0.4064)
			(end 0.7874 -0.4064)
			(stroke
				(width 0.1524)
				(type default)
			)
			(layer "F.SilkS")
		)
		(fp_line
			(start -0.7874 0.4064)
			(end -0.7874 -0.4064)
			(stroke
				(width 0.1524)
				(type default)
			)
			(layer "F.SilkS")
		)
		(fp_line
			(start 0.7874 -0.4064)
			(end 0.7874 0.4064)
			(stroke
				(width 0.1524)
				(type default)
			)
			(layer "F.SilkS")
		)
		(fp_line
			(start 0.7874 0.4064)
			(end -0.7874 0.4064)
			(stroke
				(width 0.1524)
				(type default)
			)
			(layer "F.SilkS")
		)
		(fp_line
			(start -0.67945 -0.305054)
			(end -0.12065 -0.305054)
			(stroke
				(width 0.1)
				(type default)
			)
			(layer "F.Fab")
		)
		(fp_line
			(start -0.67945 0.3048)
			(end -0.67945 -0.305054)
			(stroke
				(width 0.1)
				(type default)
			)
			(layer "F.Fab")
		)
		(fp_line
			(start -0.12065 -0.305054)
			(end -0.12065 -0.2794)
			(stroke
				(width 0.1)
				(type default)
			)
			(layer "F.Fab")
		)
		(fp_line
			(start -0.12065 -0.2794)
			(end 0.12065 -0.2794)
			(stroke
				(width 0.1)
				(type default)
			)
			(layer "F.Fab")
		)
		(fp_line
			(start -0.12065 0.2794)
			(end -0.12065 0.3048)
			(stroke
				(width 0.1)
				(type default)
			)
			(layer "F.Fab")
		)
		(fp_line
			(start -0.12065 0.3048)
			(end -0.67945 0.3048)
			(stroke
				(width 0.1)
				(type default)
			)
			(layer "F.Fab")
		)
		(fp_line
			(start 0.120396 0.2794)
			(end -0.12065 0.2794)
			(stroke
				(width 0.1)
				(type default)
			)
			(layer "F.Fab")
		)
		(fp_line
			(start 0.120396 0.3048)
			(end 0.120396 0.2794)
			(stroke
				(width 0.1)
				(type default)
			)
			(layer "F.Fab")
		)
		(fp_line
			(start 0.12065 -0.3048)
			(end 0.67945 -0.3048)
			(stroke
				(width 0.1)
				(type default)
			)
			(layer "F.Fab")
		)
		(fp_line
			(start 0.12065 -0.2794)
			(end 0.12065 -0.3048)
			(stroke
				(width 0.1)
				(type default)
			)
			(layer "F.Fab")
		)
		(fp_line
			(start 0.67945 -0.3048)
			(end 0.67945 0.3048)
			(stroke
				(width 0.1)
				(type default)
			)
			(layer "F.Fab")
		)
		(fp_line
			(start 0.67945 0.3048)
			(end 0.120396 0.3048)
			(stroke
				(width 0.1)
				(type default)
			)
			(layer "F.Fab")
		)
		(pad "1" smd circle
			(at -0.40005 0)
			(size 0 0)
			(layers "F.Cu" "F.Mask" "F.Paste")
			(net "PRSNT_NIC3_FPGA_PCA9555_N")
		)
		(pad "2" smd circle
			(at 0.40005 0)
			(size 0 0)
			(layers "F.Cu" "F.Mask" "F.Paste")
			(net "PRSNT_NIC3_FPGA_R_N")
		)
	)
	(footprint ""
		(layer "F.Cu")
		(at 331.175614 -119.477028 180)
		(property "Reference" "R881"
			(at 0 0 180)
			(layer "F.SilkS")
			(hide yes)
			(effects
				(font
					(size 1.27 1.27)
				)
			)
		)
		(property "Value" ""
			(at 0 0 180)
			(layer "F.Fab")
			(effects
				(font
					(size 1.27 1.27)
				)
			)
		)
		(duplicate_pad_numbers_are_jumpers no)
		(fp_line
			(start 0.7874 0.4064)
			(end -0.7874 0.4064)
			(stroke
				(width 0.1524)
				(type default)
			)
			(layer "F.SilkS")
		)
		(fp_line
			(start 0.7874 -0.4064)
			(end 0.7874 0.4064)
			(stroke
				(width 0.1524)
				(type default)
			)
			(layer "F.SilkS")
		)
		(fp_line
			(start -0.7874 0.4064)
			(end -0.7874 -0.4064)
			(stroke
				(width 0.1524)
				(type default)
			)
			(layer "F.SilkS")
		)
		(fp_line
			(start -0.7874 -0.4064)
			(end 0.7874 -0.4064)
			(stroke
				(width 0.1524)
				(type default)
			)
			(layer "F.SilkS")
		)
		(fp_line
			(start 0.67945 0.3048)
			(end 0.120396 0.3048)
			(stroke
				(width 0.1)
				(type default)
			)
			(layer "F.Fab")
		)
		(fp_line
			(start 0.67945 -0.3048)
			(end 0.67945 0.3048)
			(stroke
				(width 0.1)
				(type default)
			)
			(layer "F.Fab")
		)
		(fp_line
			(start 0.12065 -0.2794)
			(end 0.12065 -0.3048)
			(stroke
				(width 0.1)
				(type default)
			)
			(layer "F.Fab")
		)
		(fp_line
			(start 0.12065 -0.3048)
			(end 0.67945 -0.3048)
			(stroke
				(width 0.1)
				(type default)
			)
			(layer "F.Fab")
		)
		(fp_line
			(start 0.120396 0.3048)
			(end 0.120396 0.2794)
			(stroke
				(width 0.1)
				(type default)
			)
			(layer "F.Fab")
		)
		(fp_line
			(start 0.120396 0.2794)
			(end -0.12065 0.2794)
			(stroke
				(width 0.1)
				(type default)
			)
			(layer "F.Fab")
		)
		(fp_line
			(start -0.12065 0.3048)
			(end -0.67945 0.3048)
			(stroke
				(width 0.1)
				(type default)
			)
			(layer "F.Fab")
		)
		(fp_line
			(start -0.12065 0.2794)
			(end -0.12065 0.3048)
			(stroke
				(width 0.1)
				(type default)
			)
			(layer "F.Fab")
		)
		(fp_line
			(start -0.12065 -0.2794)
			(end 0.12065 -0.2794)
			(stroke
				(width 0.1)
				(type default)
			)
			(layer "F.Fab")
		)
		(fp_line
			(start -0.12065 -0.305054)
			(end -0.12065 -0.2794)
			(stroke
				(width 0.1)
				(type default)
			)
			(layer "F.Fab")
		)
		(fp_line
			(start -0.67945 0.3048)
			(end -0.67945 -0.305054)
			(stroke
				(width 0.1)
				(type default)
			)
			(layer "F.Fab")
		)
		(fp_line
			(start -0.67945 -0.305054)
			(end -0.12065 -0.305054)
			(stroke
				(width 0.1)
				(type default)
			)
			(layer "F.Fab")
		)
		(pad "1" smd circle
			(at -0.40005 0 180)
			(size 0 0)
			(layers "F.Cu" "F.Mask" "F.Paste")
			(net "P3V3_NIC5")
		)
		(pad "2" smd circle
			(at 0.40005 0 180)
			(size 0 0)
			(layers "F.Cu" "F.Mask" "F.Paste")
			(net "PWRGD_P3V3_NIC5")
		)
	)
	(footprint ""
		(layer "F.Cu")
		(at 440.34964 -304.036476 90)
		(property "Reference" "R1456"
			(at 0 0 90)
			(layer "F.SilkS")
			(hide yes)
			(effects
				(font
					(size 1.27 1.27)
				)
			)
		)
		(property "Value" ""
			(at 0 0 90)
			(layer "F.Fab")
			(effects
				(font
					(size 1.27 1.27)
				)
			)
		)
		(duplicate_pad_numbers_are_jumpers no)
		(fp_line
			(start 0.7874 -0.4064)
			(end 0.7874 0.4064)
			(stroke
				(width 0.1524)
				(type default)
			)
			(layer "F.SilkS")
		)
		(fp_line
			(start -0.7874 -0.4064)
			(end 0.7874 -0.4064)
			(stroke
				(width 0.1524)
				(type default)
			)
			(layer "F.SilkS")
		)
		(fp_line
			(start 0.7874 0.4064)
			(end -0.7874 0.4064)
			(stroke
				(width 0.1524)
				(type default)
			)
			(layer "F.SilkS")
		)
		(fp_line
			(start -0.7874 0.4064)
			(end -0.7874 -0.4064)
			(stroke
				(width 0.1524)
				(type default)
			)
			(layer "F.SilkS")
		)
		(fp_line
			(start -0.12065 -0.305054)
			(end -0.12065 -0.2794)
			(stroke
				(width 0.1)
				(type default)
			)
			(layer "F.Fab")
		)
		(fp_line
			(start -0.67945 -0.305054)
			(end -0.12065 -0.305054)
			(stroke
				(width 0.1)
				(type default)
			)
			(layer "F.Fab")
		)
		(fp_line
			(start 0.67945 -0.3048)
			(end 0.67945 0.3048)
			(stroke
				(width 0.1)
				(type default)
			)
			(layer "F.Fab")
		)
		(fp_line
			(start 0.12065 -0.3048)
			(end 0.67945 -0.3048)
			(stroke
				(width 0.1)
				(type default)
			)
			(layer "F.Fab")
		)
		(fp_line
			(start 0.12065 -0.2794)
			(end 0.12065 -0.3048)
			(stroke
				(width 0.1)
				(type default)
			)
			(layer "F.Fab")
		)
		(fp_line
			(start -0.12065 -0.2794)
			(end 0.12065 -0.2794)
			(stroke
				(width 0.1)
				(type default)
			)
			(layer "F.Fab")
		)
		(fp_line
			(start 0.120396 0.2794)
			(end -0.12065 0.2794)
			(stroke
				(width 0.1)
				(type default)
			)
			(layer "F.Fab")
		)
		(fp_line
			(start -0.12065 0.2794)
			(end -0.12065 0.3048)
			(stroke
				(width 0.1)
				(type default)
			)
			(layer "F.Fab")
		)
		(fp_line
			(start 0.67945 0.3048)
			(end 0.120396 0.3048)
			(stroke
				(width 0.1)
				(type default)
			)
			(layer "F.Fab")
		)
		(fp_line
			(start 0.120396 0.3048)
			(end 0.120396 0.2794)
			(stroke
				(width 0.1)
				(type default)
			)
			(layer "F.Fab")
		)
		(fp_line
			(start -0.12065 0.3048)
			(end -0.67945 0.3048)
			(stroke
				(width 0.1)
				(type default)
			)
			(layer "F.Fab")
		)
		(fp_line
			(start -0.67945 0.3048)
			(end -0.67945 -0.305054)
			(stroke
				(width 0.1)
				(type default)
			)
			(layer "F.Fab")
		)
		(pad "1" smd circle
			(at -0.40005 0 90)
			(size 0 0)
			(layers "F.Cu" "F.Mask" "F.Paste")
			(net "GND")
		)
		(pad "2" smd circle
			(at 0.40005 0 90)
			(size 0 0)
			(layers "F.Cu" "F.Mask" "F.Paste")
			(net "PEX3_SPARE6")
		)
	)
	(footprint ""
		(layer "F.Cu")
		(at 261.622286 -250.070874 -90)
		(property "Reference" "R1339"
			(at 0 0 270)
			(layer "F.SilkS")
			(hide yes)
			(effects
				(font
					(size 1.27 1.27)
				)
			)
		)
		(property "Value" ""
			(at 0 0 270)
			(layer "F.Fab")
			(effects
				(font
					(size 1.27 1.27)
				)
			)
		)
		(duplicate_pad_numbers_are_jumpers no)
		(fp_line
			(start -0.7874 0.4064)
			(end -0.7874 -0.4064)
			(stroke
				(width 0.1524)
				(type default)
			)
			(layer "F.SilkS")
		)
		(fp_line
			(start 0.7874 0.4064)
			(end -0.7874 0.4064)
			(stroke
				(width 0.1524)
				(type default)
			)
			(layer "F.SilkS")
		)
		(fp_line
			(start -0.7874 -0.4064)
			(end 0.7874 -0.4064)
			(stroke
				(width 0.1524)
				(type default)
			)
			(layer "F.SilkS")
		)
		(fp_line
			(start 0.7874 -0.4064)
			(end 0.7874 0.4064)
			(stroke
				(width 0.1524)
				(type default)
			)
			(layer "F.SilkS")
		)
		(fp_line
			(start -0.67945 0.3048)
			(end -0.67945 -0.305054)
			(stroke
				(width 0.1)
				(type default)
			)
			(layer "F.Fab")
		)
		(fp_line
			(start -0.12065 0.3048)
			(end -0.67945 0.3048)
			(stroke
				(width 0.1)
				(type default)
			)
			(layer "F.Fab")
		)
		(fp_line
			(start 0.120396 0.3048)
			(end 0.120396 0.2794)
			(stroke
				(width 0.1)
				(type default)
			)
			(layer "F.Fab")
		)
		(fp_line
			(start 0.67945 0.3048)
			(end 0.120396 0.3048)
			(stroke
				(width 0.1)
				(type default)
			)
			(layer "F.Fab")
		)
		(fp_line
			(start -0.12065 0.2794)
			(end -0.12065 0.3048)
			(stroke
				(width 0.1)
				(type default)
			)
			(layer "F.Fab")
		)
		(fp_line
			(start 0.120396 0.2794)
			(end -0.12065 0.2794)
			(stroke
				(width 0.1)
				(type default)
			)
			(layer "F.Fab")
		)
		(fp_line
			(start -0.12065 -0.2794)
			(end 0.12065 -0.2794)
			(stroke
				(width 0.1)
				(type default)
			)
			(layer "F.Fab")
		)
		(fp_line
			(start 0.12065 -0.2794)
			(end 0.12065 -0.3048)
			(stroke
				(width 0.1)
				(type default)
			)
			(layer "F.Fab")
		)
		(fp_line
			(start 0.12065 -0.3048)
			(end 0.67945 -0.3048)
			(stroke
				(width 0.1)
				(type default)
			)
			(layer "F.Fab")
		)
		(fp_line
			(start 0.67945 -0.3048)
			(end 0.67945 0.3048)
			(stroke
				(width 0.1)
				(type default)
			)
			(layer "F.Fab")
		)
		(fp_line
			(start -0.67945 -0.305054)
			(end -0.12065 -0.305054)
			(stroke
				(width 0.1)
				(type default)
			)
			(layer "F.Fab")
		)
		(fp_line
			(start -0.12065 -0.305054)
			(end -0.12065 -0.2794)
			(stroke
				(width 0.1)
				(type default)
			)
			(layer "F.Fab")
		)
		(pad "1" smd circle
			(at -0.40005 0 270)
			(size 0 0)
			(layers "F.Cu" "F.Mask" "F.Paste")
			(net "PEX2_MODE_SEL3")
		)
		(pad "2" smd circle
			(at 0.40005 0 270)
			(size 0 0)
			(layers "F.Cu" "F.Mask" "F.Paste")
			(net "P1V8_PEX")
		)
	)
	(footprint ""
		(layer "F.Cu")
		(at 373.658384 -252.356874 -90)
		(property "Reference" "R1432"
			(at 0 0 270)
			(layer "F.SilkS")
			(hide yes)
			(effects
				(font
					(size 1.27 1.27)
				)
			)
		)
		(property "Value" ""
			(at 0 0 270)
			(layer "F.Fab")
			(effects
				(font
					(size 1.27 1.27)
				)
			)
		)
		(duplicate_pad_numbers_are_jumpers no)
		(fp_line
			(start -0.7874 0.4064)
			(end -0.7874 -0.4064)
			(stroke
				(width 0.1524)
				(type default)
			)
			(layer "F.SilkS")
		)
		(fp_line
			(start 0.7874 0.4064)
			(end -0.7874 0.4064)
			(stroke
				(width 0.1524)
				(type default)
			)
			(layer "F.SilkS")
		)
		(fp_line
			(start -0.7874 -0.4064)
			(end 0.7874 -0.4064)
			(stroke
				(width 0.1524)
				(type default)
			)
			(layer "F.SilkS")
		)
		(fp_line
			(start 0.7874 -0.4064)
			(end 0.7874 0.4064)
			(stroke
				(width 0.1524)
				(type default)
			)
			(layer "F.SilkS")
		)
		(fp_line
			(start -0.67945 0.3048)
			(end -0.67945 -0.305054)
			(stroke
				(width 0.1)
				(type default)
			)
			(layer "F.Fab")
		)
		(fp_line
			(start -0.12065 0.3048)
			(end -0.67945 0.3048)
			(stroke
				(width 0.1)
				(type default)
			)
			(layer "F.Fab")
		)
		(fp_line
			(start 0.120396 0.3048)
			(end 0.120396 0.2794)
			(stroke
				(width 0.1)
				(type default)
			)
			(layer "F.Fab")
		)
		(fp_line
			(start 0.67945 0.3048)
			(end 0.120396 0.3048)
			(stroke
				(width 0.1)
				(type default)
			)
			(layer "F.Fab")
		)
		(fp_line
			(start -0.12065 0.2794)
			(end -0.12065 0.3048)
			(stroke
				(width 0.1)
				(type default)
			)
			(layer "F.Fab")
		)
		(fp_line
			(start 0.120396 0.2794)
			(end -0.12065 0.2794)
			(stroke
				(width 0.1)
				(type default)
			)
			(layer "F.Fab")
		)
		(fp_line
			(start -0.12065 -0.2794)
			(end 0.12065 -0.2794)
			(stroke
				(width 0.1)
				(type default)
			)
			(layer "F.Fab")
		)
		(fp_line
			(start 0.12065 -0.2794)
			(end 0.12065 -0.3048)
			(stroke
				(width 0.1)
				(type default)
			)
			(layer "F.Fab")
		)
		(fp_line
			(start 0.12065 -0.3048)
			(end 0.67945 -0.3048)
			(stroke
				(width 0.1)
				(type default)
			)
			(layer "F.Fab")
		)
		(fp_line
			(start 0.67945 -0.3048)
			(end 0.67945 0.3048)
			(stroke
				(width 0.1)
				(type default)
			)
			(layer "F.Fab")
		)
		(fp_line
			(start -0.67945 -0.305054)
			(end -0.12065 -0.305054)
			(stroke
				(width 0.1)
				(type default)
			)
			(layer "F.Fab")
		)
		(fp_line
			(start -0.12065 -0.305054)
			(end -0.12065 -0.2794)
			(stroke
				(width 0.1)
				(type default)
			)
			(layer "F.Fab")
		)
		(pad "1" smd circle
			(at -0.40005 0 270)
			(size 0 0)
			(layers "F.Cu" "F.Mask" "F.Paste")
			(net "GND")
		)
		(pad "2" smd circle
			(at 0.40005 0 270)
			(size 0 0)
			(layers "F.Cu" "F.Mask" "F.Paste")
			(net "PEX3_MODE_SEL7")
		)
	)
)
